# SCM (Grand Teton) — schematic netlist excerpt (pin names and nets, part order shuffled) for the footprints in the layout excerpt that follows; sources: Cadence DE-HDL packaged netlist, KiCad conversion of 12092022_DA0F0TMDCD0_F0T_Management_Board_D_brd_V3_OCP.brd

R703  Q_RES  0 5% CHIP  pkg 0402LF  page 28 : A = PWRGD_DSW_PWROK ; B = PWRGD_DSW_PWROK_R3
R843  Q_RES  4.7K 1% CHIP  pkg 0402LF  page 27 : A = P3V3_AUX ; B = SMB_BMC_ALERT10_N

(kicad_pcb
	(version 20260206)
	(generator "pcbnew")
	(generator_version "10.0")
	(general
		(thickness 1.6)
		(legacy_teardrops no)
	)
	(paper "A4")
	(title_block
		(title "12092022_DA0F0TMDCD0_F0T_Management_Board_D_brd_V3_OCP.brd")
		(comment 1 "Grand Teton / footprints 1270-1271 of 1440")
	)
	(layers
		(0 "F.Cu" signal "TOP")
		(4 "In1.Cu" signal "GND")
		(6 "In2.Cu" signal "IN1")
		(8 "In3.Cu" signal "GND1")
		(10 "In4.Cu" signal "IN2")
		(12 "In5.Cu" signal "VCC")
		(14 "In6.Cu" signal "VCC1")
		(16 "In7.Cu" signal "IN3")
		(18 "In8.Cu" signal "GND2")
		(20 "In9.Cu" signal "IN4")
		(22 "In10.Cu" signal "GND3")
		(2 "B.Cu" signal "BOTTOM")
		(9 "F.Adhes" user "F.Adhesive")
		(11 "B.Adhes" user "B.Adhesive")
		(13 "F.Paste" user "Package Geometry/Pastemask Top")
		(15 "B.Paste" user "Package Geometry/Pastemask Bottom")
		(5 "F.SilkS" user "Ref Des/Silkscreen Top")
		(7 "B.SilkS" user "Ref Des/Silkscreen Bottom")
		(1 "F.Mask" user "Board Geometry/Soldermask Top")
		(3 "B.Mask" user "Board Geometry/Soldermask Bottom")
		(17 "Dwgs.User" user "User.Drawings")
		(19 "Cmts.User" user "User.Comments")
		(21 "Eco1.User" user "User.Eco1")
		(23 "Eco2.User" user "User.Eco2")
		(25 "Edge.Cuts" user "Board Geometry/Outline")
		(27 "Margin" user)
		(31 "F.CrtYd" user "Package Geometry/Place Bound Top")
		(29 "B.CrtYd" user "Package Geometry/Place Bound Bottom")
		(35 "F.Fab" user "Ref Des/Assembly Top")
		(33 "B.Fab" user "Ref Des/Assembly Bottom")
	)
	(footprint ""
		(layer "B.Cu")
		(at 51.2445 -88.7095 180)
		(property "Reference" "R703"
			(at 0 0 0)
			(layer "B.SilkS")
			(hide yes)
			(effects
				(font
					(size 1.27 1.27)
				)
				(justify mirror)
			)
		)
		(property "Value" ""
			(at 0 0 0)
			(layer "B.Fab")
			(effects
				(font
					(size 1.27 1.27)
				)
				(justify mirror)
			)
		)
		(duplicate_pad_numbers_are_jumpers no)
		(fp_line
			(start 0.7874 0.4064)
			(end 0.7874 -0.4064)
			(stroke
				(width 0.1524)
				(type default)
			)
			(layer "B.SilkS")
		)
		(fp_line
			(start 0.7874 -0.4064)
			(end -0.7874 -0.4064)
			(stroke
				(width 0.1524)
				(type default)
			)
			(layer "B.SilkS")
		)
		(fp_line
			(start -0.7874 0.4064)
			(end 0.7874 0.4064)
			(stroke
				(width 0.1524)
				(type default)
			)
			(layer "B.SilkS")
		)
		(fp_line
			(start -0.7874 -0.4064)
			(end -0.7874 0.4064)
			(stroke
				(width 0.1524)
				(type default)
			)
			(layer "B.SilkS")
		)
		(fp_line
			(start 0.67945 0.3048)
			(end 0.67945 -0.305054)
			(stroke
				(width 0.1)
				(type default)
			)
			(layer "B.Fab")
		)
		(fp_line
			(start 0.67945 -0.305054)
			(end 0.12065 -0.305054)
			(stroke
				(width 0.1)
				(type default)
			)
			(layer "B.Fab")
		)
		(fp_line
			(start 0.12065 0.3048)
			(end 0.67945 0.3048)
			(stroke
				(width 0.1)
				(type default)
			)
			(layer "B.Fab")
		)
		(fp_line
			(start 0.12065 0.2794)
			(end 0.12065 0.3048)
			(stroke
				(width 0.1)
				(type default)
			)
			(layer "B.Fab")
		)
		(fp_line
			(start 0.12065 -0.2794)
			(end -0.12065 -0.2794)
			(stroke
				(width 0.1)
				(type default)
			)
			(layer "B.Fab")
		)
		(fp_line
			(start 0.12065 -0.305054)
			(end 0.12065 -0.2794)
			(stroke
				(width 0.1)
				(type default)
			)
			(layer "B.Fab")
		)
		(fp_line
			(start -0.120396 0.3048)
			(end -0.120396 0.2794)
			(stroke
				(width 0.1)
				(type default)
			)
			(layer "B.Fab")
		)
		(fp_line
			(start -0.120396 0.2794)
			(end 0.12065 0.2794)
			(stroke
				(width 0.1)
				(type default)
			)
			(layer "B.Fab")
		)
		(fp_line
			(start -0.12065 -0.2794)
			(end -0.12065 -0.3048)
			(stroke
				(width 0.1)
				(type default)
			)
			(layer "B.Fab")
		)
		(fp_line
			(start -0.12065 -0.3048)
			(end -0.67945 -0.3048)
			(stroke
				(width 0.1)
				(type default)
			)
			(layer "B.Fab")
		)
		(fp_line
			(start -0.67945 0.3048)
			(end -0.120396 0.3048)
			(stroke
				(width 0.1)
				(type default)
			)
			(layer "B.Fab")
		)
		(fp_line
			(start -0.67945 -0.3048)
			(end -0.67945 0.3048)
			(stroke
				(width 0.1)
				(type default)
			)
			(layer "B.Fab")
		)
		(pad "1" smd circle
			(at 0.40005 0)
			(size 0 0)
			(layers "B.Cu" "B.Mask" "B.Paste")
			(net "PWRGD_DSW_PWROK")
		)
		(pad "2" smd circle
			(at -0.40005 0)
			(size 0 0)
			(layers "B.Cu" "B.Mask" "B.Paste")
			(net "PWRGD_DSW_PWROK_R3")
		)
	)
	(footprint ""
		(layer "B.Cu")
		(at 47.51578 -66.27114 90)
		(property "Reference" "R843"
			(at 0 0 90)
			(layer "B.SilkS")
			(hide yes)
			(effects
				(font
					(size 1.27 1.27)
				)
				(justify mirror)
			)
		)
		(property "Value" ""
			(at 0 0 90)
			(layer "B.Fab")
			(effects
				(font
					(size 1.27 1.27)
				)
				(justify mirror)
			)
		)
		(duplicate_pad_numbers_are_jumpers no)
		(fp_line
			(start 0.7874 -0.4064)
			(end -0.7874 -0.4064)
			(stroke
				(width 0.1524)
				(type default)
			)
			(layer "B.SilkS")
		)
		(fp_line
			(start -0.7874 -0.4064)
			(end -0.7874 0.4064)
			(stroke
				(width 0.1524)
				(type default)
			)
			(layer "B.SilkS")
		)
		(fp_line
			(start 0.7874 0.4064)
			(end 0.7874 -0.4064)
			(stroke
				(width 0.1524)
				(type default)
			)
			(layer "B.SilkS")
		)
		(fp_line
			(start -0.7874 0.4064)
			(end 0.7874 0.4064)
			(stroke
				(width 0.1524)
				(type default)
			)
			(layer "B.SilkS")
		)
		(fp_line
			(start 0.67945 -0.305054)
			(end 0.12065 -0.305054)
			(stroke
				(width 0.1)
				(type default)
			)
			(layer "B.Fab")
		)
		(fp_line
			(start 0.12065 -0.305054)
			(end 0.12065 -0.2794)
			(stroke
				(width 0.1)
				(type default)
			)
			(layer "B.Fab")
		)
		(fp_line
			(start -0.12065 -0.3048)
			(end -0.67945 -0.3048)
			(stroke
				(width 0.1)
				(type default)
			)
			(layer "B.Fab")
		)
		(fp_line
			(start -0.67945 -0.3048)
			(end -0.67945 0.3048)
			(stroke
				(width 0.1)
				(type default)
			)
			(layer "B.Fab")
		)
		(fp_line
			(start 0.12065 -0.2794)
			(end -0.12065 -0.2794)
			(stroke
				(width 0.1)
				(type default)
			)
			(layer "B.Fab")
		)
		(fp_line
			(start -0.12065 -0.2794)
			(end -0.12065 -0.3048)
			(stroke
				(width 0.1)
				(type default)
			)
			(layer "B.Fab")
		)
		(fp_line
			(start 0.12065 0.2794)
			(end 0.12065 0.3048)
			(stroke
				(width 0.1)
				(type default)
			)
			(layer "B.Fab")
		)
		(fp_line
			(start -0.120396 0.2794)
			(end 0.12065 0.2794)
			(stroke
				(width 0.1)
				(type default)
			)
			(layer "B.Fab")
		)
		(fp_line
			(start 0.67945 0.3048)
			(end 0.67945 -0.305054)
			(stroke
				(width 0.1)
				(type default)
			)
			(layer "B.Fab")
		)
		(fp_line
			(start 0.12065 0.3048)
			(end 0.67945 0.3048)
			(stroke
				(width 0.1)
				(type default)
			)
			(layer "B.Fab")
		)
		(fp_line
			(start -0.120396 0.3048)
			(end -0.120396 0.2794)
			(stroke
				(width 0.1)
				(type default)
			)
			(layer "B.Fab")
		)
		(fp_line
			(start -0.67945 0.3048)
			(end -0.120396 0.3048)
			(stroke
				(width 0.1)
				(type default)
			)
			(layer "B.Fab")
		)
		(pad "1" smd circle
			(at 0.40005 0 270)
			(size 0 0)
			(layers "B.Cu" "B.Mask" "B.Paste")
			(net "P3V3_AUX")
		)
		(pad "2" smd circle
			(at -0.40005 0 270)
			(size 0 0)
			(layers "B.Cu" "B.Mask" "B.Paste")
			(net "SMB_BMC_ALERT10_N")
		)
	)
)
